(kicad_pcb
	(version 20260206)
	(generator "pcbnew")
	(generator_version "10.0")
	(general
		(thickness 1.6)
		(legacy_teardrops no)
	)
	(paper "A4")
	(title_block
		(title "Bryce Canyon_R.DPB_16317-1_OCP.brd")
		(comment 1 "Bryce Canyon / footprints 1152-1155 of 2099")
	)
	(layers
		(0 "F.Cu" signal "TOP")
		(4 "In1.Cu" signal "L2GND")
		(6 "In2.Cu" signal "L3")
		(8 "In3.Cu" signal "L4VCC")
		(10 "In4.Cu" signal "L5VCC")
		(12 "In5.Cu" signal "L6")
		(14 "In6.Cu" signal "L7GND")
		(2 "B.Cu" signal "BOTTOM")
		(9 "F.Adhes" user "F.Adhesive")
		(11 "B.Adhes" user "B.Adhesive")
		(13 "F.Paste" user "Package Geometry/Pastemask Top")
		(15 "B.Paste" user "Package Geometry/Pastemask Bottom")
		(5 "F.SilkS" user "Ref Des/Silkscreen Top")
		(7 "B.SilkS" user "Ref Des/Silkscreen Bottom")
		(1 "F.Mask" user "Board Geometry/Soldermask Top")
		(3 "B.Mask" user "Board Geometry/Soldermask Bottom")
		(17 "Dwgs.User" user "User.Drawings")
		(19 "Cmts.User" user "User.Comments")
		(21 "Eco1.User" user "User.Eco1")
		(23 "Eco2.User" user "User.Eco2")
		(25 "Edge.Cuts" user "Board Geometry/Outline")
		(27 "Margin" user)
		(31 "F.CrtYd" user "Package Geometry/Place Bound Top")
		(29 "B.CrtYd" user "Package Geometry/Place Bound Bottom")
		(35 "F.Fab" user "Ref Des/Assembly Top")
		(33 "B.Fab" user "Ref Des/Assembly Bottom")
	)
	(footprint ""
		(layer "F.Cu")
		(at 149.987 -148.209)
		(property "Reference" "R437"
			(at 0 0 0)
			(layer "F.SilkS")
			(hide yes)
			(effects
				(font
					(size 1.27 1.27)
				)
			)
		)
		(property "Value" "2R6F-GP"
			(at -0.0508 -4.8514 0)
			(unlocked yes)
			(layer "F.Fab")
			(hide yes)
			(effects
				(font
					(size 1.016 1.016)
					(thickness 0.1524)
				)
			)
		)
		(property "Device Type" "R1206H26"
			(at 0 -6.3754 0)
			(unlocked yes)
			(layer "F.Fab")
			(hide yes)
			(effects
				(font
					(size 1.016 1.016)
					(thickness 0.1524)
				)
			)
		)
		(duplicate_pad_numbers_are_jumpers no)
		(fp_line
			(start -1.016 -2.2352)
			(end 1.016 -2.2352)
			(stroke
				(width 0.1524)
				(type default)
			)
			(layer "F.SilkS")
		)
		(fp_line
			(start -1.016 2.2352)
			(end -1.016 -2.2352)
			(stroke
				(width 0.1524)
				(type default)
			)
			(layer "F.SilkS")
		)
		(fp_line
			(start 1.016 -2.2352)
			(end 1.016 2.2352)
			(stroke
				(width 0.1524)
				(type default)
			)
			(layer "F.SilkS")
		)
		(fp_line
			(start 1.016 2.2352)
			(end -1.016 2.2352)
			(stroke
				(width 0.1524)
				(type default)
			)
			(layer "F.SilkS")
		)
		(fp_rect
			(start -1.0922 2.3114)
			(end 1.0922 -2.3114)
			(stroke
				(width 0)
				(type default)
			)
			(fill no)
			(layer "F.CrtYd")
		)
		(fp_poly
			(pts
				(xy -1.0922 -2.3114) (xy 1.0922 -2.3114) (xy 1.0922 2.3114) (xy -1.0922 2.3114)
			)
			(stroke
				(width 0)
				(type default)
			)
			(fill no)
			(layer "F.Fab")
		)
		(pad "1" smd rect
			(at 0 -1.397)
			(size 1.651 1.27)
			(layers "F.Cu" "F.Mask" "F.Paste")
			(net "P5V_HDD16")
		)
		(pad "2" smd rect
			(at 0 1.397)
			(size 1.651 1.27)
			(layers "F.Cu" "F.Mask" "F.Paste")
			(net "5V_PRE_16")
		)
	)
	(footprint ""
		(layer "F.Cu")
		(at 479.298 -160.401 180)
		(property "Reference" "C336"
			(at 0 0 180)
			(layer "F.SilkS")
			(hide yes)
			(effects
				(font
					(size 1.27 1.27)
				)
			)
		)
		(property "Value" "SC1U25V3KX-GP"
			(at 0 -2.8194 180)
			(unlocked yes)
			(layer "F.Fab")
			(hide yes)
			(effects
				(font
					(size 1.016 1.016)
					(thickness 0.1524)
				)
			)
		)
		(property "Device Type" "C603H36"
			(at 0 -4.3434 180)
			(unlocked yes)
			(layer "F.Fab")
			(hide yes)
			(effects
				(font
					(size 1.016 1.016)
					(thickness 0.1524)
				)
			)
		)
		(duplicate_pad_numbers_are_jumpers no)
		(fp_line
			(start 0.508 0)
			(end -0.508 0)
			(stroke
				(width 0.2032)
				(type default)
			)
			(layer "F.SilkS")
		)
		(fp_rect
			(start -0.5842 1.3335)
			(end 0.5842 -1.3335)
			(stroke
				(width 0)
				(type default)
			)
			(fill no)
			(layer "F.CrtYd")
		)
		(fp_rect
			(start -0.5842 1.3335)
			(end 0.5842 -1.3335)
			(stroke
				(width 0)
				(type default)
			)
			(fill no)
			(layer "F.Fab")
		)
		(pad "1" smd custom
			(at 0 -0.762 180)
			(size 0.2159 0.2159)
			(layers "F.Cu" "F.Mask" "F.Paste")
			(net "P12V_HDD23")
			(options
				(clearance outline)
				(anchor circle)
			)
			(primitives
				(gr_poly
					(pts
						(arc
							(start -0.3302 -0.4318)
							(mid -0.402042 -0.402042)
							(end -0.4318 -0.3302)
						)
						(arc
							(start -0.4318 0.3302)
							(mid -0.402042 0.402042)
							(end -0.3302 0.4318)
						)
						(arc
							(start 0.3302 0.4318)
							(mid 0.402042 0.402042)
							(end 0.4318 0.3302)
						)
						(arc
							(start 0.4318 -0.3302)
							(mid 0.402042 -0.402042)
							(end 0.3302 -0.4318)
						)
					)
					(width 0)
					(fill yes)
				)
			)
		)
		(pad "2" smd custom
			(at 0 0.762 180)
			(size 0.2159 0.2159)
			(layers "F.Cu" "F.Mask" "F.Paste")
			(net "GND")
			(options
				(clearance outline)
				(anchor circle)
			)
			(primitives
				(gr_poly
					(pts
						(arc
							(start -0.3302 -0.4318)
							(mid -0.402042 -0.402042)
							(end -0.4318 -0.3302)
						)
						(arc
							(start -0.4318 0.3302)
							(mid -0.402042 0.402042)
							(end -0.3302 0.4318)
						)
						(arc
							(start 0.3302 0.4318)
							(mid 0.402042 0.402042)
							(end 0.4318 0.3302)
						)
						(arc
							(start 0.4318 -0.3302)
							(mid 0.402042 -0.402042)
							(end 0.3302 -0.4318)
						)
					)
					(width 0)
					(fill yes)
				)
			)
		)
	)
	(footprint ""
		(layer "F.Cu")
		(at 96.393 -31.6484 180)
		(property "Reference" "R668"
			(at 0 0 180)
			(layer "F.SilkS")
			(hide yes)
			(effects
				(font
					(size 1.27 1.27)
				)
			)
		)
		(property "Value" "10KR2F-2-GP"
			(at 0.064008 -3.993896 180)
			(unlocked yes)
			(layer "F.Fab")
			(hide yes)
			(effects
				(font
					(size 1.016 1.016)
					(thickness 0.1524)
				)
			)
		)
		(property "Device Type" "R402H16"
			(at 0.064008 -5.517896 180)
			(unlocked yes)
			(layer "F.Fab")
			(hide yes)
			(effects
				(font
					(size 1.016 1.016)
					(thickness 0.1524)
				)
			)
		)
		(duplicate_pad_numbers_are_jumpers no)
		(fp_line
			(start 0.508 -0.9398)
			(end -0.508 -0.9398)
			(stroke
				(width 0.1524)
				(type default)
			)
			(layer "F.SilkS")
		)
		(fp_line
			(start -0.508 -0.9398)
			(end -0.508 0.9398)
			(stroke
				(width 0.1524)
				(type default)
			)
			(layer "F.SilkS")
		)
		(fp_rect
			(start -0.508 0.9398)
			(end 0.508 -0.9398)
			(stroke
				(width 0)
				(type default)
			)
			(fill no)
			(layer "F.CrtYd")
		)
		(fp_rect
			(start -0.508 0.9398)
			(end 0.508 -0.9398)
			(stroke
				(width 0)
				(type default)
			)
			(fill no)
			(layer "F.Fab")
		)
		(pad "1" smd custom
			(at 0 -0.4445 180)
			(size 0.1397 0.1397)
			(layers "F.Cu" "F.Mask" "F.Paste")
			(net "P3V3_STBY_B")
			(options
				(clearance outline)
				(anchor circle)
			)
			(primitives
				(gr_poly
					(pts
						(arc
							(start -0.1778 -0.2794)
							(mid -0.249642 -0.249642)
							(end -0.2794 -0.1778)
						)
						(arc
							(start -0.2794 0.1778)
							(mid -0.249642 0.249642)
							(end -0.1778 0.2794)
						)
						(arc
							(start 0.1778 0.2794)
							(mid 0.249642 0.249642)
							(end 0.2794 0.1778)
						)
						(arc
							(start 0.2794 -0.1778)
							(mid 0.249642 -0.249642)
							(end 0.1778 -0.2794)
						)
					)
					(width 0)
					(fill yes)
				)
			)
		)
		(pad "2" smd custom
			(at 0 0.4445 180)
			(size 0.1397 0.1397)
			(layers "F.Cu" "F.Mask" "F.Paste")
			(net "HDD_PRSNT_26")
			(options
				(clearance outline)
				(anchor circle)
			)
			(primitives
				(gr_poly
					(pts
						(arc
							(start -0.1778 -0.2794)
							(mid -0.249642 -0.249642)
							(end -0.2794 -0.1778)
						)
						(arc
							(start -0.2794 0.1778)
							(mid -0.249642 0.249642)
							(end -0.1778 0.2794)
						)
						(arc
							(start 0.1778 0.2794)
							(mid 0.249642 0.249642)
							(end 0.2794 0.1778)
						)
						(arc
							(start 0.2794 -0.1778)
							(mid 0.249642 -0.249642)
							(end 0.1778 -0.2794)
						)
					)
					(width 0)
					(fill yes)
				)
			)
		)
	)
	(footprint ""
		(layer "F.Cu")
		(at 477.4692 -250.571)
		(property "Reference" "C176"
			(at 0 0 0)
			(layer "F.SilkS")
			(hide yes)
			(effects
				(font
					(size 1.27 1.27)
				)
			)
		)
		(property "Value" "SCD01U50V2KX-1GP"
			(at 1.1811 -2.7051 0)
			(unlocked yes)
			(layer "F.Fab")
			(hide yes)
			(effects
				(font
					(size 1.016 1.016)
					(thickness 0.1524)
				)
			)
		)
		(property "Device Type" "C402H22"
			(at 1.1811 -4.2291 0)
			(unlocked yes)
			(layer "F.Fab")
			(hide yes)
			(effects
				(font
					(size 1.016 1.016)
					(thickness 0.1524)
				)
			)
		)
		(duplicate_pad_numbers_are_jumpers no)
		(fp_rect
			(start -0.4318 0.9525)
			(end 0.4318 -0.9525)
			(stroke
				(width 0)
				(type default)
			)
			(fill no)
			(layer "F.CrtYd")
		)
		(fp_rect
			(start -0.4318 0.9525)
			(end 0.4318 -0.9525)
			(stroke
				(width 0)
				(type default)
			)
			(fill no)
			(layer "F.Fab")
		)
		(pad "1" smd custom
			(at 0 -0.4445)
			(size 0.1524 0.1524)
			(layers "F.Cu" "F.Mask" "F.Paste")
			(net "HDD_PRSNT_11")
			(options
				(clearance outline)
				(anchor circle)
			)
			(primitives
				(gr_poly
					(pts
						(arc
							(start 0.3048 -0.2032)
							(mid 0.275042 -0.275042)
							(end 0.2032 -0.3048)
						)
						(arc
							(start -0.2032 -0.3048)
							(mid -0.275042 -0.275042)
							(end -0.3048 -0.2032)
						)
						(arc
							(start -0.3048 0.2032)
							(mid -0.275042 0.275042)
							(end -0.2032 0.3048)
						)
						(arc
							(start 0.2032 0.3048)
							(mid 0.275042 0.275042)
							(end 0.3048 0.2032)
						)
					)
					(width 0)
					(fill yes)
				)
			)
		)
		(pad "2" smd custom
			(at 0 0.4445)
			(size 0.1524 0.1524)
			(layers "F.Cu" "F.Mask" "F.Paste")
			(net "GND")
			(options
				(clearance outline)
				(anchor circle)
			)
			(primitives
				(gr_poly
					(pts
						(arc
							(start 0.3048 -0.2032)
							(mid 0.275042 -0.275042)
							(end 0.2032 -0.3048)
						)
						(arc
							(start -0.2032 -0.3048)
							(mid -0.275042 -0.275042)
							(end -0.3048 -0.2032)
						)
						(arc
							(start -0.3048 0.2032)
							(mid -0.275042 0.275042)
							(end -0.2032 0.3048)
						)
						(arc
							(start 0.2032 0.3048)
							(mid 0.275042 0.275042)
							(end 0.3048 0.2032)
						)
					)
					(width 0)
					(fill yes)
				)
			)
		)
	)
)
